(kicad_pcb
	(version 20260206)
	(generator "pcbnew")
	(generator_version "10.0")
	(general
		(thickness 1.6)
		(legacy_teardrops no)
	)
	(paper "A4")
	(title_block
		(title "peb — Lightning_PEB_BRD.brd")
		(comment 1 "Lightning (Wiwynn / Facebook NVMe JBOF) / footprints 155-161 of 2563")
	)
	(layers
		(0 "F.Cu" signal "TOP")
		(4 "In1.Cu" signal "L2GND")
		(6 "In2.Cu" signal "L3")
		(8 "In3.Cu" signal "L4VCC")
		(10 "In4.Cu" signal "L5VCC")
		(12 "In5.Cu" signal "L6")
		(14 "In6.Cu" signal "L7GND")
		(2 "B.Cu" signal "BOTTOM")
		(9 "F.Adhes" user "F.Adhesive")
		(11 "B.Adhes" user "B.Adhesive")
		(13 "F.Paste" user "Package Geometry/Pastemask Top")
		(15 "B.Paste" user "Package Geometry/Pastemask Bottom")
		(5 "F.SilkS" user "Ref Des/Silkscreen Top")
		(7 "B.SilkS" user "Ref Des/Silkscreen Bottom")
		(1 "F.Mask" user "Board Geometry/Soldermask Top")
		(3 "B.Mask" user "Board Geometry/Soldermask Bottom")
		(17 "Dwgs.User" user "User.Drawings")
		(19 "Cmts.User" user "User.Comments")
		(21 "Eco1.User" user "User.Eco1")
		(23 "Eco2.User" user "User.Eco2")
		(25 "Edge.Cuts" user "Board Geometry/Outline")
		(27 "Margin" user)
		(31 "F.CrtYd" user "Package Geometry/Place Bound Top")
		(29 "B.CrtYd" user "Package Geometry/Place Bound Bottom")
		(35 "F.Fab" user "Ref Des/Assembly Top")
		(33 "B.Fab" user "Ref Des/Assembly Bottom")
	)
	(footprint ""
		(layer "F.Cu")
		(at 12.954 -111.633 -90)
		(property "Reference" "PC81"
			(at 0 0 270)
			(layer "F.SilkS")
			(hide yes)
			(effects
				(font
					(size 1.27 1.27)
				)
			)
		)
		(property "Value" "SC22U6D3V5MX-5-GP"
			(at -0.0762 -6.1214 270)
			(unlocked yes)
			(layer "F.Fab")
			(hide yes)
			(effects
				(font
					(size 1.016 1.016)
					(thickness 0.1524)
				)
			)
		)
		(property "Device Type" "C805H56"
			(at -0.0762 -8.1534 270)
			(unlocked yes)
			(layer "F.Fab")
			(hide yes)
			(effects
				(font
					(size 1.016 1.016)
					(thickness 0.1524)
				)
			)
		)
		(duplicate_pad_numbers_are_jumpers no)
		(fp_line
			(start 0.635 0)
			(end -0.635 0)
			(stroke
				(width 0.508)
				(type default)
			)
			(layer "F.SilkS")
		)
		(fp_rect
			(start -0.9652 1.778)
			(end 0.9652 -1.778)
			(stroke
				(width 0)
				(type default)
			)
			(fill no)
			(layer "F.CrtYd")
		)
		(fp_poly
			(pts
				(xy -0.9652 -1.778) (xy 0.9652 -1.778) (xy 0.9652 1.778) (xy -0.9652 1.778)
			)
			(stroke
				(width 0)
				(type default)
			)
			(fill no)
			(layer "F.Fab")
		)
		(pad "1" smd rect
			(at 0 -0.9652 270)
			(size 1.397 1.143)
			(layers "F.Cu" "F.Mask" "F.Paste")
			(net "P1V26_PWR")
		)
		(pad "2" smd rect
			(at 0 0.9652 270)
			(size 1.397 1.143)
			(layers "F.Cu" "F.Mask" "F.Paste")
			(net "GND")
		)
	)
	(footprint ""
		(layer "F.Cu")
		(at 20.7264 -173.2026 90)
		(property "Reference" "PR38"
			(at 0 0 90)
			(layer "F.SilkS")
			(hide yes)
			(effects
				(font
					(size 1.27 1.27)
				)
			)
		)
		(property "Value" "10KR2F-2-GP"
			(at 0.064008 -3.993896 90)
			(unlocked yes)
			(layer "F.Fab")
			(hide yes)
			(effects
				(font
					(size 1.016 1.016)
					(thickness 0.1524)
				)
			)
		)
		(property "Device Type" "R402H16"
			(at 0.064008 -5.517896 90)
			(unlocked yes)
			(layer "F.Fab")
			(hide yes)
			(effects
				(font
					(size 1.016 1.016)
					(thickness 0.1524)
				)
			)
		)
		(duplicate_pad_numbers_are_jumpers no)
		(fp_line
			(start 0.508 -0.9398)
			(end -0.508 -0.9398)
			(stroke
				(width 0.1524)
				(type default)
			)
			(layer "F.SilkS")
		)
		(fp_line
			(start -0.508 -0.9398)
			(end -0.508 0.9398)
			(stroke
				(width 0.1524)
				(type default)
			)
			(layer "F.SilkS")
		)
		(fp_rect
			(start -0.508 0.9398)
			(end 0.508 -0.9398)
			(stroke
				(width 0)
				(type default)
			)
			(fill no)
			(layer "F.CrtYd")
		)
		(fp_rect
			(start -0.508 0.9398)
			(end 0.508 -0.9398)
			(stroke
				(width 0)
				(type default)
			)
			(fill no)
			(layer "F.Fab")
		)
		(pad "1" smd custom
			(at 0 -0.4445 90)
			(size 0.1397 0.1397)
			(layers "F.Cu" "F.Mask" "F.Paste")
			(net "GND")
			(options
				(clearance outline)
				(anchor circle)
			)
			(primitives
				(gr_poly
					(pts
						(arc
							(start -0.1778 -0.2794)
							(mid -0.249642 -0.249642)
							(end -0.2794 -0.1778)
						)
						(arc
							(start -0.2794 0.1778)
							(mid -0.249642 0.249642)
							(end -0.1778 0.2794)
						)
						(arc
							(start 0.1778 0.2794)
							(mid 0.249642 0.249642)
							(end 0.2794 0.1778)
						)
						(arc
							(start 0.2794 -0.1778)
							(mid 0.249642 -0.249642)
							(end 0.1778 -0.2794)
						)
					)
					(width 0)
					(fill yes)
				)
			)
		)
		(pad "2" smd custom
			(at 0 0.4445 90)
			(size 0.1397 0.1397)
			(layers "F.Cu" "F.Mask" "F.Paste")
			(net "PCIE_MATED#_B")
			(options
				(clearance outline)
				(anchor circle)
			)
			(primitives
				(gr_poly
					(pts
						(arc
							(start -0.1778 -0.2794)
							(mid -0.249642 -0.249642)
							(end -0.2794 -0.1778)
						)
						(arc
							(start -0.2794 0.1778)
							(mid -0.249642 0.249642)
							(end -0.1778 0.2794)
						)
						(arc
							(start 0.1778 0.2794)
							(mid 0.249642 0.249642)
							(end 0.2794 0.1778)
						)
						(arc
							(start 0.2794 -0.1778)
							(mid 0.249642 -0.249642)
							(end 0.1778 -0.2794)
						)
					)
					(width 0)
					(fill yes)
				)
			)
		)
	)
	(footprint ""
		(layer "F.Cu")
		(at 131.421886 -51.326288 -90)
		(property "Reference" "R945"
			(at 0 0 270)
			(layer "F.SilkS")
			(hide yes)
			(effects
				(font
					(size 1.27 1.27)
				)
			)
		)
		(property "Value" "0R2J-2-GP"
			(at 0.064008 -3.993896 270)
			(unlocked yes)
			(layer "F.Fab")
			(hide yes)
			(effects
				(font
					(size 1.016 1.016)
					(thickness 0.1524)
				)
			)
		)
		(property "Device Type" "R402H16"
			(at 0.064008 -5.517896 270)
			(unlocked yes)
			(layer "F.Fab")
			(hide yes)
			(effects
				(font
					(size 1.016 1.016)
					(thickness 0.1524)
				)
			)
		)
		(duplicate_pad_numbers_are_jumpers no)
		(fp_line
			(start -0.508 -0.9398)
			(end -0.508 0.9398)
			(stroke
				(width 0.1524)
				(type default)
			)
			(layer "F.SilkS")
		)
		(fp_line
			(start 0.508 -0.9398)
			(end -0.508 -0.9398)
			(stroke
				(width 0.1524)
				(type default)
			)
			(layer "F.SilkS")
		)
		(fp_rect
			(start -0.508 0.9398)
			(end 0.508 -0.9398)
			(stroke
				(width 0)
				(type default)
			)
			(fill no)
			(layer "F.CrtYd")
		)
		(fp_rect
			(start -0.508 0.9398)
			(end 0.508 -0.9398)
			(stroke
				(width 0)
				(type default)
			)
			(fill no)
			(layer "F.Fab")
		)
		(pad "1" smd custom
			(at 0 -0.4445 270)
			(size 0.1397 0.1397)
			(layers "F.Cu" "F.Mask" "F.Paste")
			(net "PMC_R_TXD5")
			(options
				(clearance outline)
				(anchor circle)
			)
			(primitives
				(gr_poly
					(pts
						(arc
							(start -0.1778 -0.2794)
							(mid -0.249642 -0.249642)
							(end -0.2794 -0.1778)
						)
						(arc
							(start -0.2794 0.1778)
							(mid -0.249642 0.249642)
							(end -0.1778 0.2794)
						)
						(arc
							(start 0.1778 0.2794)
							(mid 0.249642 0.249642)
							(end 0.2794 0.1778)
						)
						(arc
							(start 0.2794 -0.1778)
							(mid 0.249642 -0.249642)
							(end 0.1778 -0.2794)
						)
					)
					(width 0)
					(fill yes)
				)
			)
		)
		(pad "2" smd custom
			(at 0 0.4445 270)
			(size 0.1397 0.1397)
			(layers "F.Cu" "F.Mask" "F.Paste")
			(net "EXP_SMART_TX")
			(options
				(clearance outline)
				(anchor circle)
			)
			(primitives
				(gr_poly
					(pts
						(arc
							(start -0.1778 -0.2794)
							(mid -0.249642 -0.249642)
							(end -0.2794 -0.1778)
						)
						(arc
							(start -0.2794 0.1778)
							(mid -0.249642 0.249642)
							(end -0.1778 0.2794)
						)
						(arc
							(start 0.1778 0.2794)
							(mid 0.249642 0.249642)
							(end 0.2794 0.1778)
						)
						(arc
							(start 0.2794 -0.1778)
							(mid 0.249642 -0.249642)
							(end 0.1778 -0.2794)
						)
					)
					(width 0)
					(fill yes)
				)
			)
		)
	)
	(footprint ""
		(layer "F.Cu")
		(at 230.251 -9.398 -90)
		(property "Reference" "R653"
			(at 0 0 270)
			(layer "F.SilkS")
			(hide yes)
			(effects
				(font
					(size 1.27 1.27)
				)
			)
		)
		(property "Value" "100KR2F-L1-GP"
			(at 0.064008 -3.993896 270)
			(unlocked yes)
			(layer "F.Fab")
			(hide yes)
			(effects
				(font
					(size 1.016 1.016)
					(thickness 0.1524)
				)
			)
		)
		(property "Device Type" "R402H16"
			(at 0.064008 -5.517896 270)
			(unlocked yes)
			(layer "F.Fab")
			(hide yes)
			(effects
				(font
					(size 1.016 1.016)
					(thickness 0.1524)
				)
			)
		)
		(duplicate_pad_numbers_are_jumpers no)
		(fp_line
			(start -0.508 -0.9398)
			(end -0.508 0.9398)
			(stroke
				(width 0.1524)
				(type default)
			)
			(layer "F.SilkS")
		)
		(fp_line
			(start 0.508 -0.9398)
			(end -0.508 -0.9398)
			(stroke
				(width 0.1524)
				(type default)
			)
			(layer "F.SilkS")
		)
		(fp_rect
			(start -0.508 0.9398)
			(end 0.508 -0.9398)
			(stroke
				(width 0)
				(type default)
			)
			(fill no)
			(layer "F.CrtYd")
		)
		(fp_rect
			(start -0.508 0.9398)
			(end 0.508 -0.9398)
			(stroke
				(width 0)
				(type default)
			)
			(fill no)
			(layer "F.Fab")
		)
		(pad "1" smd custom
			(at 0 -0.4445 270)
			(size 0.1397 0.1397)
			(layers "F.Cu" "F.Mask" "F.Paste")
			(net "P3V3_STBY")
			(options
				(clearance outline)
				(anchor circle)
			)
			(primitives
				(gr_poly
					(pts
						(arc
							(start -0.1778 -0.2794)
							(mid -0.249642 -0.249642)
							(end -0.2794 -0.1778)
						)
						(arc
							(start -0.2794 0.1778)
							(mid -0.249642 0.249642)
							(end -0.1778 0.2794)
						)
						(arc
							(start 0.1778 0.2794)
							(mid 0.249642 0.249642)
							(end 0.2794 0.1778)
						)
						(arc
							(start 0.2794 -0.1778)
							(mid 0.249642 -0.249642)
							(end 0.1778 -0.2794)
						)
					)
					(width 0)
					(fill yes)
				)
			)
		)
		(pad "2" smd custom
			(at 0 0.4445 270)
			(size 0.1397 0.1397)
			(layers "F.Cu" "F.Mask" "F.Paste")
			(net "EEPROM_WP_8536")
			(options
				(clearance outline)
				(anchor circle)
			)
			(primitives
				(gr_poly
					(pts
						(arc
							(start -0.1778 -0.2794)
							(mid -0.249642 -0.249642)
							(end -0.2794 -0.1778)
						)
						(arc
							(start -0.2794 0.1778)
							(mid -0.249642 0.249642)
							(end -0.1778 0.2794)
						)
						(arc
							(start 0.1778 0.2794)
							(mid 0.249642 0.249642)
							(end 0.2794 0.1778)
						)
						(arc
							(start 0.2794 -0.1778)
							(mid 0.249642 -0.249642)
							(end 0.1778 -0.2794)
						)
					)
					(width 0)
					(fill yes)
				)
			)
		)
	)
	(footprint ""
		(layer "F.Cu")
		(at 312.625486 -33.556448)
		(property "Reference" "C21"
			(at 0 0 0)
			(layer "F.SilkS")
			(hide yes)
			(effects
				(font
					(size 1.27 1.27)
				)
			)
		)
		(property "Value" "SCD22U10V2KX-1GP"
			(at 1.1811 -2.7051 0)
			(unlocked yes)
			(layer "F.Fab")
			(hide yes)
			(effects
				(font
					(size 1.016 1.016)
					(thickness 0.1524)
				)
			)
		)
		(property "Device Type" "C402H22"
			(at 1.1811 -4.2291 0)
			(unlocked yes)
			(layer "F.Fab")
			(hide yes)
			(effects
				(font
					(size 1.016 1.016)
					(thickness 0.1524)
				)
			)
		)
		(duplicate_pad_numbers_are_jumpers no)
		(fp_rect
			(start -0.4318 0.9525)
			(end 0.4318 -0.9525)
			(stroke
				(width 0)
				(type default)
			)
			(fill no)
			(layer "F.CrtYd")
		)
		(fp_rect
			(start -0.4318 0.9525)
			(end 0.4318 -0.9525)
			(stroke
				(width 0)
				(type default)
			)
			(fill no)
			(layer "F.Fab")
		)
		(pad "1" smd custom
			(at 0 -0.4445)
			(size 0.1524 0.1524)
			(layers "F.Cu" "F.Mask" "F.Paste")
			(net "PCIE_TX_CAP_P10")
			(options
				(clearance outline)
				(anchor circle)
			)
			(primitives
				(gr_poly
					(pts
						(arc
							(start 0.3048 -0.2032)
							(mid 0.275042 -0.275042)
							(end 0.2032 -0.3048)
						)
						(arc
							(start -0.2032 -0.3048)
							(mid -0.275042 -0.275042)
							(end -0.3048 -0.2032)
						)
						(arc
							(start -0.3048 0.2032)
							(mid -0.275042 0.275042)
							(end -0.2032 0.3048)
						)
						(arc
							(start 0.2032 0.3048)
							(mid 0.275042 0.275042)
							(end 0.3048 0.2032)
						)
					)
					(width 0)
					(fill yes)
				)
			)
		)
		(pad "2" smd custom
			(at 0 0.4445)
			(size 0.1524 0.1524)
			(layers "F.Cu" "F.Mask" "F.Paste")
			(net "PCIE_TX_P10")
			(options
				(clearance outline)
				(anchor circle)
			)
			(primitives
				(gr_poly
					(pts
						(arc
							(start 0.3048 -0.2032)
							(mid 0.275042 -0.275042)
							(end 0.2032 -0.3048)
						)
						(arc
							(start -0.2032 -0.3048)
							(mid -0.275042 -0.275042)
							(end -0.3048 -0.2032)
						)
						(arc
							(start -0.3048 0.2032)
							(mid -0.275042 0.275042)
							(end -0.2032 0.3048)
						)
						(arc
							(start 0.2032 0.3048)
							(mid 0.275042 0.275042)
							(end 0.3048 0.2032)
						)
					)
					(width 0)
					(fill yes)
				)
			)
		)
	)
	(footprint ""
		(layer "F.Cu")
		(at 76.835 -52.6288)
		(property "Reference" "JP13"
			(at 0 0 0)
			(layer "F.SilkS")
			(hide yes)
			(effects
				(font
					(size 1.27 1.27)
				)
			)
		)
		(property "Value" "PIN-CON3-S-GP"
			(at -5.588 -5.3086 0)
			(unlocked yes)
			(layer "F.Fab")
			(hide yes)
			(effects
				(font
					(size 1.016 1.016)
					(thickness 0.1524)
				)
			)
		)
		(property "Device Type" "21S-91-03GB01"
			(at -5.588 -6.8326 0)
			(unlocked yes)
			(layer "F.Fab")
			(hide yes)
			(effects
				(font
					(size 1.016 1.016)
					(thickness 0.1524)
				)
			)
		)
		(duplicate_pad_numbers_are_jumpers no)
		(fp_line
			(start -4.0132 -1.6256)
			(end -2.7432 -1.6256)
			(stroke
				(width 0.4064)
				(type default)
			)
			(layer "F.SilkS")
		)
		(fp_line
			(start -4.0132 -0.3556)
			(end -4.0132 -1.6256)
			(stroke
				(width 0.4064)
				(type default)
			)
			(layer "F.SilkS")
		)
		(fp_line
			(start -3.8862 -1.4986)
			(end -3.8862 1.4986)
			(stroke
				(width 0.1524)
				(type default)
			)
			(layer "F.SilkS")
		)
		(fp_line
			(start -3.8862 1.4986)
			(end 3.8862 1.4986)
			(stroke
				(width 0.1524)
				(type default)
			)
			(layer "F.SilkS")
		)
		(fp_line
			(start 3.8862 -1.4986)
			(end -3.8862 -1.4986)
			(stroke
				(width 0.1524)
				(type default)
			)
			(layer "F.SilkS")
		)
		(fp_line
			(start 3.8862 1.4986)
			(end 3.8862 -1.4986)
			(stroke
				(width 0.1524)
				(type default)
			)
			(layer "F.SilkS")
		)
		(fp_circle
			(center -2.54 0)
			(end -1.4732 0)
			(stroke
				(width 0.3048)
				(type default)
			)
			(fill no)
			(layer "F.SilkS")
		)
		(fp_circle
			(center 0 0)
			(end 1.0668 0)
			(stroke
				(width 0.3048)
				(type default)
			)
			(fill no)
			(layer "F.SilkS")
		)
		(fp_circle
			(center 2.54 0)
			(end 3.6068 0)
			(stroke
				(width 0.3048)
				(type default)
			)
			(fill no)
			(layer "F.SilkS")
		)
		(fp_rect
			(start -3.6322 1.2446)
			(end 3.6322 -1.2446)
			(stroke
				(width 0)
				(type default)
			)
			(fill no)
			(layer "F.CrtYd")
		)
		(fp_poly
			(pts
				(xy 4.1402 -1.2446) (xy -3.6322 -1.2446) (xy -3.6322 1.2446) (xy 3.6322 1.2446) (xy 3.6322 -1.2319)
				(xy 4.1402 -1.2319) (xy 4.1402 1.7526) (xy -4.1402 1.7526) (xy -4.1402 -1.7526) (xy 4.1402 -1.7526)
			)
			(stroke
				(width 0)
				(type default)
			)
			(fill no)
			(layer "F.CrtYd")
		)
		(fp_rect
			(start -4.1402 1.7526)
			(end 4.1402 -1.7526)
			(stroke
				(width 0)
				(type default)
			)
			(fill no)
			(layer "F.Fab")
		)
		(pad "1" thru_hole circle
			(at -2.54 0)
			(size 1.4224 1.4224)
			(drill 1.016)
			(layers "*.Cu" "*.Mask")
			(remove_unused_layers no)
			(net "BMC_CPU_EN")
			(clearance 0.1524)
			(thermal_gap 0.1524)
		)
		(pad "2" thru_hole circle
			(at 0 0)
			(size 1.4224 1.4224)
			(drill 1.016)
			(layers "*.Cu" "*.Mask")
			(remove_unused_layers no)
			(net "FLA_CS_R")
			(clearance 0.1524)
			(thermal_gap 0.1524)
		)
		(pad "3" thru_hole circle
			(at 2.54 0)
			(size 1.4224 1.4224)
			(drill 1.016)
			(layers "*.Cu" "*.Mask")
			(remove_unused_layers no)
			(net "BMC_CPU_DIS")
			(clearance 0.1524)
			(thermal_gap 0.1524)
		)
	)
	(footprint ""
		(layer "F.Cu")
		(at 67.0052 -165.5826 90)
		(property "Reference" "PR22"
			(at 0 0 90)
			(layer "F.SilkS")
			(hide yes)
			(effects
				(font
					(size 1.27 1.27)
				)
			)
		)
		(property "Value" "0R3J-0-U-GP"
			(at -0.0254 -2.5146 90)
			(unlocked yes)
			(layer "F.Fab")
			(hide yes)
			(effects
				(font
					(size 1.016 1.016)
					(thickness 0.1524)
				)
			)
		)
		(property "Device Type" "R603H22"
			(at -0.0254 -4.0386 90)
			(unlocked yes)
			(layer "F.Fab")
			(hide yes)
			(effects
				(font
					(size 1.016 1.016)
					(thickness 0.1524)
				)
			)
		)
		(duplicate_pad_numbers_are_jumpers no)
		(fp_line
			(start 0.2032 0)
			(end 0.4826 0)
			(stroke
				(width 0.2032)
				(type default)
			)
			(layer "F.SilkS")
		)
		(fp_line
			(start -0.4826 0)
			(end -0.2032 0)
			(stroke
				(width 0.2032)
				(type default)
			)
			(layer "F.SilkS")
		)
		(fp_rect
			(start -0.5842 1.3335)
			(end 0.5842 -1.3335)
			(stroke
				(width 0)
				(type default)
			)
			(fill no)
			(layer "F.CrtYd")
		)
		(fp_rect
			(start -0.5842 1.3335)
			(end 0.5842 -1.3335)
			(stroke
				(width 0)
				(type default)
			)
			(fill no)
			(layer "F.Fab")
		)
		(pad "1" smd custom
			(at 0 -0.762 90)
			(size 0.2159 0.2159)
			(layers "F.Cu" "F.Mask" "F.Paste")
			(net "PWRGD_P1V8_STBY")
			(options
				(clearance outline)
				(anchor circle)
			)
			(primitives
				(gr_poly
					(pts
						(arc
							(start -0.3302 -0.4318)
							(mid -0.402042 -0.402042)
							(end -0.4318 -0.3302)
						)
						(arc
							(start -0.4318 0.3302)
							(mid -0.402042 0.402042)
							(end -0.3302 0.4318)
						)
						(arc
							(start 0.3302 0.4318)
							(mid 0.402042 0.402042)
							(end 0.4318 0.3302)
						)
						(arc
							(start 0.4318 -0.3302)
							(mid 0.402042 -0.402042)
							(end 0.3302 -0.4318)
						)
					)
					(width 0)
					(fill yes)
				)
			)
		)
		(pad "2" smd custom
			(at 0 0.762 90)
			(size 0.2159 0.2159)
			(layers "F.Cu" "F.Mask" "F.Paste")
			(net "VR_P1V538_STBY_EN_R")
			(options
				(clearance outline)
				(anchor circle)
			)
			(primitives
				(gr_poly
					(pts
						(arc
							(start -0.3302 -0.4318)
							(mid -0.402042 -0.402042)
							(end -0.4318 -0.3302)
						)
						(arc
							(start -0.4318 0.3302)
							(mid -0.402042 0.402042)
							(end -0.3302 0.4318)
						)
						(arc
							(start 0.3302 0.4318)
							(mid 0.402042 0.402042)
							(end 0.4318 0.3302)
						)
						(arc
							(start 0.4318 -0.3302)
							(mid 0.402042 -0.402042)
							(end 0.3302 -0.4318)
						)
					)
					(width 0)
					(fill yes)
				)
			)
		)
	)
)
